# S9S_MB_2U (Grand Teton) — schematic netlist excerpt (pin names and nets, part order shuffled) for the footprints in the layout excerpt that follows; sources: Cadence DE-HDL packaged netlist, KiCad conversion of 03242023_DA0F0TMBIJ0_F0T_Motherboard_J_brd_V01_OCP.brd

R1661  Q_RES  33.2 1% CHIP  pkg 0402LF  page 241 : A = SMB_VR_3V3AUX_SCL ; B = SMB_VR_3V3AUX_SCL_R
R4127  Q_RES  4.7K 5% CHIP  pkg 0402LF  page 146 : A = P3V3_AUX ; B = GPU_3V3IO_RSVD1_FFU_N

(kicad_pcb
	(version 20260206)
	(generator "pcbnew")
	(generator_version "10.0")
	(general
		(thickness 1.6)
		(legacy_teardrops no)
	)
	(paper "A4")
	(title_block
		(title "03242023_DA0F0TMBIJ0_F0T_Motherboard_J_brd_V01_OCP.brd")
		(comment 1 "Grand Teton / footprints 551-552 of 6105")
	)
	(layers
		(0 "F.Cu" signal "TOP")
		(4 "In1.Cu" signal "GND")
		(6 "In2.Cu" signal "IN1")
		(8 "In3.Cu" signal "GND1")
		(10 "In4.Cu" signal "IN2")
		(12 "In5.Cu" signal "GND2")
		(14 "In6.Cu" signal "IN3")
		(16 "In7.Cu" signal "GND3")
		(18 "In8.Cu" signal "VCC")
		(20 "In9.Cu" signal "VCC1")
		(22 "In10.Cu" signal "GND4")
		(24 "In11.Cu" signal "IN4")
		(26 "In12.Cu" signal "GND5")
		(28 "In13.Cu" signal "IN5")
		(30 "In14.Cu" signal "GND6")
		(32 "In15.Cu" signal "IN6")
		(34 "In16.Cu" signal "GND7")
		(2 "B.Cu" signal "BOTTOM")
		(9 "F.Adhes" user "F.Adhesive")
		(11 "B.Adhes" user "B.Adhesive")
		(13 "F.Paste" user "Package Geometry/Pastemask Top")
		(15 "B.Paste" user "Package Geometry/Pastemask Bottom")
		(5 "F.SilkS" user "Ref Des/Silkscreen Top")
		(7 "B.SilkS" user "Ref Des/Silkscreen Bottom")
		(1 "F.Mask" user "Board Geometry/Soldermask Top")
		(3 "B.Mask" user "Board Geometry/Soldermask Bottom")
		(17 "Dwgs.User" user "User.Drawings")
		(19 "Cmts.User" user "User.Comments")
		(21 "Eco1.User" user "User.Eco1")
		(23 "Eco2.User" user "User.Eco2")
		(25 "Edge.Cuts" user "Board Geometry/Outline")
		(27 "Margin" user)
		(31 "F.CrtYd" user "Package Geometry/Place Bound Top")
		(29 "B.CrtYd" user "Package Geometry/Place Bound Bottom")
		(35 "F.Fab" user "Ref Des/Assembly Top")
		(33 "B.Fab" user "Ref Des/Assembly Bottom")
	)
	(footprint ""
		(layer "F.Cu")
		(at 309.259224 -438.187846 -90)
		(property "Reference" "R4127"
			(at 0 0 270)
			(layer "F.SilkS")
			(hide yes)
			(effects
				(font
					(size 1.27 1.27)
				)
			)
		)
		(property "Value" ""
			(at 0 0 270)
			(layer "F.Fab")
			(effects
				(font
					(size 1.27 1.27)
				)
			)
		)
		(duplicate_pad_numbers_are_jumpers no)
		(fp_line
			(start -0.7874 0.4064)
			(end -0.7874 -0.4064)
			(stroke
				(width 0.1524)
				(type default)
			)
			(layer "F.SilkS")
		)
		(fp_line
			(start 0.7874 0.4064)
			(end -0.7874 0.4064)
			(stroke
				(width 0.1524)
				(type default)
			)
			(layer "F.SilkS")
		)
		(fp_line
			(start -0.7874 -0.4064)
			(end 0.7874 -0.4064)
			(stroke
				(width 0.1524)
				(type default)
			)
			(layer "F.SilkS")
		)
		(fp_line
			(start 0.7874 -0.4064)
			(end 0.7874 0.4064)
			(stroke
				(width 0.1524)
				(type default)
			)
			(layer "F.SilkS")
		)
		(fp_line
			(start -0.67945 0.3048)
			(end -0.67945 -0.305054)
			(stroke
				(width 0.1)
				(type default)
			)
			(layer "F.Fab")
		)
		(fp_line
			(start -0.12065 0.3048)
			(end -0.67945 0.3048)
			(stroke
				(width 0.1)
				(type default)
			)
			(layer "F.Fab")
		)
		(fp_line
			(start 0.120396 0.3048)
			(end 0.120396 0.2794)
			(stroke
				(width 0.1)
				(type default)
			)
			(layer "F.Fab")
		)
		(fp_line
			(start 0.67945 0.3048)
			(end 0.120396 0.3048)
			(stroke
				(width 0.1)
				(type default)
			)
			(layer "F.Fab")
		)
		(fp_line
			(start -0.12065 0.2794)
			(end -0.12065 0.3048)
			(stroke
				(width 0.1)
				(type default)
			)
			(layer "F.Fab")
		)
		(fp_line
			(start 0.120396 0.2794)
			(end -0.12065 0.2794)
			(stroke
				(width 0.1)
				(type default)
			)
			(layer "F.Fab")
		)
		(fp_line
			(start -0.12065 -0.2794)
			(end 0.12065 -0.2794)
			(stroke
				(width 0.1)
				(type default)
			)
			(layer "F.Fab")
		)
		(fp_line
			(start 0.12065 -0.2794)
			(end 0.12065 -0.3048)
			(stroke
				(width 0.1)
				(type default)
			)
			(layer "F.Fab")
		)
		(fp_line
			(start 0.12065 -0.3048)
			(end 0.67945 -0.3048)
			(stroke
				(width 0.1)
				(type default)
			)
			(layer "F.Fab")
		)
		(fp_line
			(start 0.67945 -0.3048)
			(end 0.67945 0.3048)
			(stroke
				(width 0.1)
				(type default)
			)
			(layer "F.Fab")
		)
		(fp_line
			(start -0.67945 -0.305054)
			(end -0.12065 -0.305054)
			(stroke
				(width 0.1)
				(type default)
			)
			(layer "F.Fab")
		)
		(fp_line
			(start -0.12065 -0.305054)
			(end -0.12065 -0.2794)
			(stroke
				(width 0.1)
				(type default)
			)
			(layer "F.Fab")
		)
		(pad "1" smd circle
			(at -0.40005 0 270)
			(size 0 0)
			(layers "F.Cu" "F.Mask" "F.Paste")
			(net "P3V3_AUX")
		)
		(pad "2" smd circle
			(at 0.40005 0 270)
			(size 0 0)
			(layers "F.Cu" "F.Mask" "F.Paste")
			(net "GPU_3V3IO_RSVD1_FFU_N")
		)
	)
	(footprint ""
		(layer "F.Cu")
		(at 35.840162 -122.380502 90)
		(property "Reference" "R1661"
			(at 0 0 90)
			(layer "F.SilkS")
			(hide yes)
			(effects
				(font
					(size 1.27 1.27)
				)
			)
		)
		(property "Value" ""
			(at 0 0 90)
			(layer "F.Fab")
			(effects
				(font
					(size 1.27 1.27)
				)
			)
		)
		(duplicate_pad_numbers_are_jumpers no)
		(fp_line
			(start 0.7874 -0.4064)
			(end 0.7874 0.4064)
			(stroke
				(width 0.1524)
				(type default)
			)
			(layer "F.SilkS")
		)
		(fp_line
			(start -0.7874 -0.4064)
			(end 0.7874 -0.4064)
			(stroke
				(width 0.1524)
				(type default)
			)
			(layer "F.SilkS")
		)
		(fp_line
			(start 0.7874 0.4064)
			(end -0.7874 0.4064)
			(stroke
				(width 0.1524)
				(type default)
			)
			(layer "F.SilkS")
		)
		(fp_line
			(start -0.7874 0.4064)
			(end -0.7874 -0.4064)
			(stroke
				(width 0.1524)
				(type default)
			)
			(layer "F.SilkS")
		)
		(fp_line
			(start -0.12065 -0.305054)
			(end -0.12065 -0.2794)
			(stroke
				(width 0.1)
				(type default)
			)
			(layer "F.Fab")
		)
		(fp_line
			(start -0.67945 -0.305054)
			(end -0.12065 -0.305054)
			(stroke
				(width 0.1)
				(type default)
			)
			(layer "F.Fab")
		)
		(fp_line
			(start 0.67945 -0.3048)
			(end 0.67945 0.3048)
			(stroke
				(width 0.1)
				(type default)
			)
			(layer "F.Fab")
		)
		(fp_line
			(start 0.12065 -0.3048)
			(end 0.67945 -0.3048)
			(stroke
				(width 0.1)
				(type default)
			)
			(layer "F.Fab")
		)
		(fp_line
			(start 0.12065 -0.2794)
			(end 0.12065 -0.3048)
			(stroke
				(width 0.1)
				(type default)
			)
			(layer "F.Fab")
		)
		(fp_line
			(start -0.12065 -0.2794)
			(end 0.12065 -0.2794)
			(stroke
				(width 0.1)
				(type default)
			)
			(layer "F.Fab")
		)
		(fp_line
			(start 0.120396 0.2794)
			(end -0.12065 0.2794)
			(stroke
				(width 0.1)
				(type default)
			)
			(layer "F.Fab")
		)
		(fp_line
			(start -0.12065 0.2794)
			(end -0.12065 0.3048)
			(stroke
				(width 0.1)
				(type default)
			)
			(layer "F.Fab")
		)
		(fp_line
			(start 0.67945 0.3048)
			(end 0.120396 0.3048)
			(stroke
				(width 0.1)
				(type default)
			)
			(layer "F.Fab")
		)
		(fp_line
			(start 0.120396 0.3048)
			(end 0.120396 0.2794)
			(stroke
				(width 0.1)
				(type default)
			)
			(layer "F.Fab")
		)
		(fp_line
			(start -0.12065 0.3048)
			(end -0.67945 0.3048)
			(stroke
				(width 0.1)
				(type default)
			)
			(layer "F.Fab")
		)
		(fp_line
			(start -0.67945 0.3048)
			(end -0.67945 -0.305054)
			(stroke
				(width 0.1)
				(type default)
			)
			(layer "F.Fab")
		)
		(pad "1" smd circle
			(at -0.40005 0 90)
			(size 0 0)
			(layers "F.Cu" "F.Mask" "F.Paste")
			(net "SMB_VR_3V3AUX_SCL")
		)
		(pad "2" smd circle
			(at 0.40005 0 90)
			(size 0 0)
			(layers "F.Cu" "F.Mask" "F.Paste")
			(net "SMB_VR_3V3AUX_SCL_R")
		)
	)
)
